(kicad_pcb
	(version 20241229)
	(generator "pcbnew")
	(generator_version "9.0")
	(general
		(thickness 1.711)
		(legacy_teardrops no)
	)
	(paper "A4")
	(title_block
		(title "Antmicro Baseboard for Jetson AGX Thor")
		(date "2026-02-18")
		(rev "1.1.0")
		(company "Antmicro Ltd")
		(comment 1 "www.antmicro.com")
		(comment 9 "footprints 1005-1009 of 1170")
	)
	(layers
		(0 "F.Cu" signal)
		(4 "In1.Cu" signal)
		(6 "In2.Cu" signal)
		(8 "In3.Cu" signal)
		(10 "In4.Cu" jumper)
		(12 "In5.Cu" signal)
		(14 "In6.Cu" signal)
		(16 "In7.Cu" signal)
		(18 "In8.Cu" signal)
		(2 "B.Cu" signal)
		(9 "F.Adhes" user "F.Adhesive")
		(11 "B.Adhes" user "B.Adhesive")
		(13 "F.Paste" user)
		(15 "B.Paste" user)
		(5 "F.SilkS" user "F.Silkscreen")
		(7 "B.SilkS" user "B.Silkscreen")
		(1 "F.Mask" user)
		(3 "B.Mask" user)
		(17 "Dwgs.User" user "User.Drawings")
		(19 "Cmts.User" user "User.Comments")
		(21 "Eco1.User" user "User.Eco1")
		(23 "Eco2.User" user "User.Eco2")
		(25 "Edge.Cuts" user)
		(27 "Margin" user)
		(31 "F.CrtYd" user "F.Courtyard")
		(29 "B.CrtYd" user "B.Courtyard")
		(35 "F.Fab" user)
		(33 "B.Fab" user)
	)
	(footprint "antmicro-footprints:C_0402_1005Metric"
		(layer "B.Cu")
		(at 121.93 70.67)
		(descr "Capacitor SMD 0402")
		(tags "capacitor SMD 0402")
		(property "Reference" "C13"
			(at -0.73 0.63 0)
			(layer "B.SilkS")
			(effects
				(font
					(size 0.7 0.7)
					(thickness 0.15)
				)
				(justify right top mirror)
			)
		)
		(property "Value" "C_10u_0402"
			(at -1.022927 -2.155213 0)
			(layer "B.Fab")
			(effects
				(font
					(size 0.7 0.7)
					(thickness 0.15)
				)
				(justify right top mirror)
			)
		)
		(property "Datasheet" "https://www.yageo.com/en/Chart/Download/pdf/CC0402MRX5R5BB106"
			(at 0 0 0)
			(layer "B.Fab")
			(hide yes)
			(effects
				(font
					(size 1.27 1.27)
					(thickness 0.15)
				)
				(justify mirror)
			)
		)
		(property "Description" "SMD Multilayer Ceramic Capacitor, 10 µF, 6.3 V, 0402 [1005 Metric], ± 20%, X5R, CC Series"
			(at 0 0 0)
			(layer "B.Fab")
			(hide yes)
			(effects
				(font
					(size 1.27 1.27)
					(thickness 0.15)
				)
				(justify mirror)
			)
		)
		(property "MPN" "CC0402MRX5R5BB106"
			(at 0 0 0)
			(unlocked yes)
			(layer "B.Fab")
			(hide yes)
			(effects
				(font
					(size 1 1)
					(thickness 0.15)
				)
				(justify mirror)
			)
		)
		(property "Manufacturer" "YAGEO"
			(at 0 0 0)
			(unlocked yes)
			(layer "B.Fab")
			(hide yes)
			(effects
				(font
					(size 1 1)
					(thickness 0.15)
				)
				(justify mirror)
			)
		)
		(property "License" "Apache-2.0"
			(at 0 0 0)
			(unlocked yes)
			(layer "B.Fab")
			(hide yes)
			(effects
				(font
					(size 1 1)
					(thickness 0.15)
				)
				(justify mirror)
			)
		)
		(property "Author" "Antmicro"
			(at 0 0 0)
			(unlocked yes)
			(layer "B.Fab")
			(hide yes)
			(effects
				(font
					(size 1 1)
					(thickness 0.15)
				)
				(justify mirror)
			)
		)
		(property "Val" "10u"
			(at 0 0 0)
			(unlocked yes)
			(layer "B.Fab")
			(hide yes)
			(effects
				(font
					(size 1 1)
					(thickness 0.15)
				)
				(justify mirror)
			)
		)
		(property "Voltage" ""
			(at 0 0 0)
			(unlocked yes)
			(layer "B.Fab")
			(hide yes)
			(effects
				(font
					(size 1 1)
					(thickness 0.15)
				)
				(justify mirror)
			)
		)
		(property "Dielectric" "template_dielectric"
			(at 0 0 0)
			(unlocked yes)
			(layer "B.Fab")
			(hide yes)
			(effects
				(font
					(size 1 1)
					(thickness 0.15)
				)
				(justify mirror)
			)
		)
		(sheetname "/SoM_Power/")
		(sheetfile "som_power.kicad_sch")
		(attr smd)
		(fp_rect
			(start -0.925 0.47)
			(end 0.925 -0.47)
			(stroke
				(width 0.05)
				(type default)
			)
			(fill no)
			(layer "B.CrtYd")
		)
		(fp_line
			(start -0.494 -0.248)
			(end -0.494 0.25)
			(stroke
				(width 0.15)
				(type solid)
			)
			(layer "B.Fab")
		)
		(fp_line
			(start -0.494 0.25)
			(end 0.504 0.25)
			(stroke
				(width 0.15)
				(type solid)
			)
			(layer "B.Fab")
		)
		(fp_line
			(start 0.504 -0.248)
			(end -0.494 -0.248)
			(stroke
				(width 0.15)
				(type solid)
			)
			(layer "B.Fab")
		)
		(fp_line
			(start 0.504 0.25)
			(end 0.504 -0.248)
			(stroke
				(width 0.15)
				(type solid)
			)
			(layer "B.Fab")
		)
		(fp_text user "${REFERENCE}"
			(at -0.939 -4.599 0)
			(layer "B.Fab")
			(effects
				(font
					(size 0.7 0.7)
					(thickness 0.15)
				)
				(justify right top mirror)
			)
		)
		(fp_text user "Author: Antmicro"
			(at -0.939 -3.399 0)
			(layer "B.Fab")
			(effects
				(font
					(size 0.7 0.7)
					(thickness 0.15)
				)
				(justify right top mirror)
			)
		)
		(fp_text user "License: Apache-2.0"
			(at -0.939 -5.799 0)
			(layer "B.Fab")
			(effects
				(font
					(size 0.7 0.7)
					(thickness 0.15)
				)
				(justify right top mirror)
			)
		)
		(pad "1" smd roundrect
			(at -0.48 0)
			(size 0.59 0.64)
			(layers "B.Cu" "B.Mask" "B.Paste")
			(roundrect_rratio 0.25)
			(net 1 "GND")
			(pintype "passive")
		)
		(pad "2" smd roundrect
			(at 0.48 0)
			(size 0.59 0.64)
			(layers "B.Cu" "B.Mask" "B.Paste")
			(roundrect_rratio 0.25)
			(net 213 "+5V_SOM")
			(pintype "passive")
		)
	)
	(footprint "antmicro-footprints:C_0402_1005Metric"
		(layer "B.Cu")
		(at 215.826 145.4 180)
		(descr "Capacitor SMD 0402")
		(tags "capacitor SMD 0402")
		(property "Reference" "C172"
			(at -1.29 -1.77 0)
			(layer "B.SilkS")
			(effects
				(font
					(size 0.7 0.7)
					(thickness 0.15)
				)
				(justify left bottom mirror)
			)
		)
		(property "Value" "C_100n_0402"
			(at -1.022927 -2.155213 0)
			(layer "B.Fab")
			(effects
				(font
					(size 0.7 0.7)
					(thickness 0.15)
				)
				(justify left bottom mirror)
			)
		)
		(property "Datasheet" "https://www.murata.com/products/productdetail?partno=GRM155R61H104KE14%23"
			(at 0 0 0)
			(layer "B.Fab")
			(hide yes)
			(effects
				(font
					(size 1.27 1.27)
					(thickness 0.15)
				)
				(justify mirror)
			)
		)
		(property "Description" "SMD Multilayer Ceramic Capacitor, 0.1 µF, 50 V, 0402 [1005 Metric], ± 10%, X5R, GRM Series"
			(at 0 0 0)
			(layer "B.Fab")
			(hide yes)
			(effects
				(font
					(size 1.27 1.27)
					(thickness 0.15)
				)
				(justify mirror)
			)
		)
		(property "MPN" "GRM155R61H104KE14D"
			(at 0 0 0)
			(unlocked yes)
			(layer "B.Fab")
			(hide yes)
			(effects
				(font
					(size 1 1)
					(thickness 0.15)
				)
				(justify mirror)
			)
		)
		(property "Manufacturer" "Murata"
			(at 0 0 0)
			(unlocked yes)
			(layer "B.Fab")
			(hide yes)
			(effects
				(font
					(size 1 1)
					(thickness 0.15)
				)
				(justify mirror)
			)
		)
		(property "License" "Apache-2.0"
			(at 0 0 0)
			(unlocked yes)
			(layer "B.Fab")
			(hide yes)
			(effects
				(font
					(size 1 1)
					(thickness 0.15)
				)
				(justify mirror)
			)
		)
		(property "Author" "Antmicro"
			(at 0 0 0)
			(unlocked yes)
			(layer "B.Fab")
			(hide yes)
			(effects
				(font
					(size 1 1)
					(thickness 0.15)
				)
				(justify mirror)
			)
		)
		(property "Val" "100n"
			(at 0 0 0)
			(unlocked yes)
			(layer "B.Fab")
			(hide yes)
			(effects
				(font
					(size 1 1)
					(thickness 0.15)
				)
				(justify mirror)
			)
		)
		(property "Voltage" "50V"
			(at 0 0 0)
			(unlocked yes)
			(layer "B.Fab")
			(hide yes)
			(effects
				(font
					(size 1 1)
					(thickness 0.15)
				)
				(justify mirror)
			)
		)
		(property "Dielectric" "X5R"
			(at 0 0 0)
			(unlocked yes)
			(layer "B.Fab")
			(hide yes)
			(effects
				(font
					(size 1 1)
					(thickness 0.15)
				)
				(justify mirror)
			)
		)
		(sheetname "/SFP/")
		(sheetfile "sfp.kicad_sch")
		(attr smd)
		(fp_poly
			(pts
				(xy -0.925 0.47) (xy -0.925 -0.47) (xy 0.925 -0.47) (xy 0.925 0.47)
			)
			(stroke
				(width 0.05)
				(type default)
			)
			(fill no)
			(layer "B.CrtYd")
		)
		(fp_line
			(start 0.504 0.25)
			(end 0.504 -0.248)
			(stroke
				(width 0.15)
				(type solid)
			)
			(layer "B.Fab")
		)
		(fp_line
			(start 0.504 -0.248)
			(end -0.494 -0.248)
			(stroke
				(width 0.15)
				(type solid)
			)
			(layer "B.Fab")
		)
		(fp_line
			(start -0.494 0.25)
			(end 0.504 0.25)
			(stroke
				(width 0.15)
				(type solid)
			)
			(layer "B.Fab")
		)
		(fp_line
			(start -0.494 -0.248)
			(end -0.494 0.25)
			(stroke
				(width 0.15)
				(type solid)
			)
			(layer "B.Fab")
		)
		(fp_text user "Author: Antmicro"
			(at -0.939 -3.399 0)
			(layer "B.Fab")
			(effects
				(font
					(size 0.7 0.7)
					(thickness 0.15)
				)
				(justify left bottom mirror)
			)
		)
		(fp_text user "License: Apache-2.0"
			(at -0.939 -5.799 0)
			(layer "B.Fab")
			(effects
				(font
					(size 0.7 0.7)
					(thickness 0.15)
				)
				(justify left bottom mirror)
			)
		)
		(fp_text user "${REFERENCE}"
			(at -0.939 -4.599 0)
			(layer "B.Fab")
			(effects
				(font
					(size 0.7 0.7)
					(thickness 0.15)
				)
				(justify left bottom mirror)
			)
		)
		(pad "1" smd roundrect
			(at -0.48 0 180)
			(size 0.59 0.64)
			(layers "B.Cu" "B.Mask" "B.Paste")
			(roundrect_rratio 0.25)
			(net 1 "GND")
			(pintype "passive")
		)
		(pad "2" smd roundrect
			(at 0.48 0 180)
			(size 0.59 0.64)
			(layers "B.Cu" "B.Mask" "B.Paste")
			(roundrect_rratio 0.25)
			(net 379 "/SFP/SH")
			(pintype "passive")
		)
	)
	(footprint "antmicro-footprints:C_0402_1005Metric"
		(layer "B.Cu")
		(at 178.37 88.85 180)
		(descr "Capacitor SMD 0402")
		(tags "capacitor SMD 0402")
		(property "Reference" "C263"
			(at 3.64 -0.43 0)
			(layer "B.SilkS")
			(effects
				(font
					(size 0.7 0.7)
					(thickness 0.15)
				)
				(justify left bottom mirror)
			)
		)
		(property "Value" "C_100n_0402"
			(at -1.022927 -2.155213 0)
			(layer "B.Fab")
			(effects
				(font
					(size 0.7 0.7)
					(thickness 0.15)
				)
				(justify left bottom mirror)
			)
		)
		(property "Datasheet" "https://www.murata.com/products/productdetail?partno=GRM155R61H104KE14%23"
			(at 0 0 0)
			(layer "B.Fab")
			(hide yes)
			(effects
				(font
					(size 1.27 1.27)
					(thickness 0.15)
				)
				(justify mirror)
			)
		)
		(property "Description" "SMD Multilayer Ceramic Capacitor, 0.1 µF, 50 V, 0402 [1005 Metric], ± 10%, X5R, GRM Series"
			(at 0 0 0)
			(layer "B.Fab")
			(hide yes)
			(effects
				(font
					(size 1.27 1.27)
					(thickness 0.15)
				)
				(justify mirror)
			)
		)
		(property "MPN" "GRM155R61H104KE14D"
			(at 0 0 0)
			(unlocked yes)
			(layer "B.Fab")
			(hide yes)
			(effects
				(font
					(size 1 1)
					(thickness 0.15)
				)
				(justify mirror)
			)
		)
		(property "Val" "100n"
			(at 0 0 0)
			(unlocked yes)
			(layer "B.Fab")
			(hide yes)
			(effects
				(font
					(size 1 1)
					(thickness 0.15)
				)
				(justify mirror)
			)
		)
		(property "Voltage" "50V"
			(at 0 0 0)
			(unlocked yes)
			(layer "B.Fab")
			(hide yes)
			(effects
				(font
					(size 1 1)
					(thickness 0.15)
				)
				(justify mirror)
			)
		)
		(property "Dielectric" "X5R"
			(at 0 0 0)
			(unlocked yes)
			(layer "B.Fab")
			(hide yes)
			(effects
				(font
					(size 1 1)
					(thickness 0.15)
				)
				(justify mirror)
			)
		)
		(property "Manufacturer" "Murata"
			(at 0 0 0)
			(unlocked yes)
			(layer "B.Fab")
			(hide yes)
			(effects
				(font
					(size 1 1)
					(thickness 0.15)
				)
				(justify mirror)
			)
		)
		(property "License" "Apache-2.0"
			(at 0 0 0)
			(unlocked yes)
			(layer "B.Fab")
			(hide yes)
			(effects
				(font
					(size 1 1)
					(thickness 0.15)
				)
				(justify mirror)
			)
		)
		(property "Author" "Antmicro"
			(at 0 0 0)
			(unlocked yes)
			(layer "B.Fab")
			(hide yes)
			(effects
				(font
					(size 1 1)
					(thickness 0.15)
				)
				(justify mirror)
			)
		)
		(sheetname "/Power/")
		(sheetfile "power.kicad_sch")
		(attr smd)
		(fp_rect
			(start -0.925 0.47)
			(end 0.925 -0.47)
			(stroke
				(width 0.05)
				(type default)
			)
			(fill no)
			(layer "B.CrtYd")
		)
		(fp_line
			(start 0.504 0.25)
			(end 0.504 -0.248)
			(stroke
				(width 0.15)
				(type solid)
			)
			(layer "B.Fab")
		)
		(fp_line
			(start 0.504 -0.248)
			(end -0.494 -0.248)
			(stroke
				(width 0.15)
				(type solid)
			)
			(layer "B.Fab")
		)
		(fp_line
			(start -0.494 0.25)
			(end 0.504 0.25)
			(stroke
				(width 0.15)
				(type solid)
			)
			(layer "B.Fab")
		)
		(fp_line
			(start -0.494 -0.248)
			(end -0.494 0.25)
			(stroke
				(width 0.15)
				(type solid)
			)
			(layer "B.Fab")
		)
		(fp_text user "Author: Antmicro"
			(at -0.939 -3.399 0)
			(layer "B.Fab")
			(effects
				(font
					(size 0.7 0.7)
					(thickness 0.15)
				)
				(justify left bottom mirror)
			)
		)
		(fp_text user "${REFERENCE}"
			(at -0.939 -4.599 0)
			(layer "B.Fab")
			(effects
				(font
					(size 0.7 0.7)
					(thickness 0.15)
				)
				(justify left bottom mirror)
			)
		)
		(fp_text user "License: Apache-2.0"
			(at -0.939 -5.799 0)
			(layer "B.Fab")
			(effects
				(font
					(size 0.7 0.7)
					(thickness 0.15)
				)
				(justify left bottom mirror)
			)
		)
		(pad "1" smd roundrect
			(at -0.48 0 180)
			(size 0.59 0.64)
			(layers "B.Cu" "B.Mask" "B.Paste")
			(roundrect_rratio 0.25)
			(net 1 "GND")
			(pintype "passive")
		)
		(pad "2" smd roundrect
			(at 0.48 0 180)
			(size 0.59 0.64)
			(layers "B.Cu" "B.Mask" "B.Paste")
			(roundrect_rratio 0.25)
			(net 904 "+20V")
			(pintype "passive")
		)
	)
	(footprint "antmicro-footprints:R_0402_1005Metric"
		(layer "B.Cu")
		(at 76 66.5 180)
		(descr "Resistor SMD 0402")
		(tags "resistor SMD 0402")
		(property "Reference" "R275"
			(at -1.6 -2.4 0)
			(layer "B.SilkS")
			(effects
				(font
					(size 0.7 0.7)
					(thickness 0.15)
				)
				(justify left bottom mirror)
			)
		)
		(property "Value" "R_10k_0402"
			(at -1.011843 -1.772046 0)
			(layer "B.Fab")
			(effects
				(font
					(size 0.7 0.7)
					(thickness 0.15)
				)
				(justify left bottom mirror)
			)
		)
		(property "Datasheet" "https://www.bourns.com/docs/product-datasheets/cr.pdf"
			(at 0 0 0)
			(layer "B.Fab")
			(hide yes)
			(effects
				(font
					(size 1.27 1.27)
					(thickness 0.15)
				)
				(justify mirror)
			)
		)
		(property "Description" "SMD Chip Resistor, 10 kohm, ± 1%, 62.5 mW, 0402 [1005 Metric], Thick Film, General Purpose"
			(at 0 0 0)
			(layer "B.Fab")
			(hide yes)
			(effects
				(font
					(size 1.27 1.27)
					(thickness 0.15)
				)
				(justify mirror)
			)
		)
		(property "MPN" "CR0402-FX-1002GLF"
			(at 0 0 0)
			(unlocked yes)
			(layer "B.Fab")
			(hide yes)
			(effects
				(font
					(size 1 1)
					(thickness 0.15)
				)
				(justify mirror)
			)
		)
		(property "Manufacturer" "Bourns"
			(at 0 0 0)
			(unlocked yes)
			(layer "B.Fab")
			(hide yes)
			(effects
				(font
					(size 1 1)
					(thickness 0.15)
				)
				(justify mirror)
			)
		)
		(property "License" "Apache-2.0"
			(at 0 0 0)
			(unlocked yes)
			(layer "B.Fab")
			(hide yes)
			(effects
				(font
					(size 1 1)
					(thickness 0.15)
				)
				(justify mirror)
			)
		)
		(property "Author" "Antmicro"
			(at 0 0 0)
			(unlocked yes)
			(layer "B.Fab")
			(hide yes)
			(effects
				(font
					(size 1 1)
					(thickness 0.15)
				)
				(justify mirror)
			)
		)
		(property "Val" "10k"
			(at 0 0 0)
			(unlocked yes)
			(layer "B.Fab")
			(hide yes)
			(effects
				(font
					(size 1 1)
					(thickness 0.15)
				)
				(justify mirror)
			)
		)
		(property "Tolerance" "1%"
			(at 0 0 0)
			(unlocked yes)
			(layer "B.Fab")
			(hide yes)
			(effects
				(font
					(size 1 1)
					(thickness 0.15)
				)
				(justify mirror)
			)
		)
		(sheetname "/Expansion connector/")
		(sheetfile "expansion_connector.kicad_sch")
		(attr smd exclude_from_pos_files exclude_from_bom dnp)
		(fp_poly
			(pts
				(xy -0.925 0.47) (xy 0.925 0.47) (xy 0.925 -0.47) (xy -0.925 -0.47)
			)
			(stroke
				(width 0.05)
				(type default)
			)
			(fill no)
			(layer "B.CrtYd")
		)
		(fp_poly
			(pts
				(xy -0.5 0.25) (xy 0.5 0.25) (xy 0.5 -0.25) (xy -0.5 -0.25)
			)
			(stroke
				(width 0.15)
				(type solid)
			)
			(fill no)
			(layer "B.Fab")
		)
		(fp_text user "License: Apache-2.0"
			(at -0.949999 -5.169 0)
			(layer "B.Fab")
			(effects
				(font
					(size 0.7 0.7)
					(thickness 0.15)
				)
				(justify left bottom mirror)
			)
		)
		(fp_text user "${REFERENCE}"
			(at -0.95 -3.168 0)
			(layer "B.Fab")
			(effects
				(font
					(size 0.7 0.7)
					(thickness 0.15)
				)
				(justify left bottom mirror)
			)
		)
		(fp_text user "Author: Antmicro"
			(at -0.95 -4.169 0)
			(layer "B.Fab")
			(effects
				(font
					(size 0.7 0.7)
					(thickness 0.15)
				)
				(justify left bottom mirror)
			)
		)
		(pad "1" smd roundrect
			(at -0.48 0 180)
			(size 0.59 0.64)
			(layers "B.Cu" "B.Mask" "B.Paste")
			(roundrect_rratio 0.25)
			(net 341 "/Expansion connector/FMC_PRESENT")
			(pintype "passive")
		)
		(pad "2" smd roundrect
			(at 0.48 0 180)
			(size 0.59 0.64)
			(layers "B.Cu" "B.Mask" "B.Paste")
			(roundrect_rratio 0.25)
			(net 295 "/Expansion connector/+V_{ADJ}")
			(pintype "passive")
		)
	)
	(footprint "antmicro-footprints:R_0402_1005Metric"
		(layer "B.Cu")
		(at 144.6 65.2 -90)
		(descr "Resistor SMD 0402")
		(tags "resistor SMD 0402")
		(property "Reference" "R243"
			(at 0.8 -0.4 90)
			(layer "B.SilkS")
			(effects
				(font
					(size 0.7 0.7)
					(thickness 0.15)
				)
				(justify left bottom mirror)
			)
		)
		(property "Value" "R_10k_0402"
			(at -1.011843 -1.772046 90)
			(layer "B.Fab")
			(effects
				(font
					(size 0.7 0.7)
					(thickness 0.15)
				)
				(justify left bottom mirror)
			)
		)
		(property "Datasheet" "https://www.bourns.com/docs/product-datasheets/cr.pdf"
			(at 0 0 90)
			(layer "B.Fab")
			(hide yes)
			(effects
				(font
					(size 1.27 1.27)
					(thickness 0.15)
				)
				(justify mirror)
			)
		)
		(property "Description" "SMD Chip Resistor, 10 kohm, ± 1%, 62.5 mW, 0402 [1005 Metric], Thick Film, General Purpose"
			(at 0 0 90)
			(layer "B.Fab")
			(hide yes)
			(effects
				(font
					(size 1.27 1.27)
					(thickness 0.15)
				)
				(justify mirror)
			)
		)
		(property "Manufacturer" "Bourns"
			(at 0 0 90)
			(unlocked yes)
			(layer "B.Fab")
			(hide yes)
			(effects
				(font
					(size 1 1)
					(thickness 0.15)
				)
				(justify mirror)
			)
		)
		(property "MPN" "CR0402-FX-1002GLF"
			(at 0 0 90)
			(unlocked yes)
			(layer "B.Fab")
			(hide yes)
			(effects
				(font
					(size 1 1)
					(thickness 0.15)
				)
				(justify mirror)
			)
		)
		(property "Val" "10k"
			(at 0 0 90)
			(unlocked yes)
			(layer "B.Fab")
			(hide yes)
			(effects
				(font
					(size 1 1)
					(thickness 0.15)
				)
				(justify mirror)
			)
		)
		(property "License" "Apache-2.0"
			(at 0 0 90)
			(unlocked yes)
			(layer "B.Fab")
			(hide yes)
			(effects
				(font
					(size 1 1)
					(thickness 0.15)
				)
				(justify mirror)
			)
		)
		(property "Author" "Antmicro"
			(at 0 0 90)
			(unlocked yes)
			(layer "B.Fab")
			(hide yes)
			(effects
				(font
					(size 1 1)
					(thickness 0.15)
				)
				(justify mirror)
			)
		)
		(property "Tolerance" "1%"
			(at 0 0 90)
			(unlocked yes)
			(layer "B.Fab")
			(hide yes)
			(effects
				(font
					(size 1 1)
					(thickness 0.15)
				)
				(justify mirror)
			)
		)
		(sheetname "/Peripherals/")
		(sheetfile "peripherals.kicad_sch")
		(attr smd)
		(fp_poly
			(pts
				(xy -0.925 0.47) (xy 0.925 0.47) (xy 0.925 -0.47) (xy -0.925 -0.47)
			)
			(stroke
				(width 0.05)
				(type default)
			)
			(fill no)
			(layer "B.CrtYd")
		)
		(fp_poly
			(pts
				(xy -0.5 0.25) (xy 0.5 0.25) (xy 0.5 -0.25) (xy -0.5 -0.25)
			)
			(stroke
				(width 0.15)
				(type solid)
			)
			(fill no)
			(layer "B.Fab")
		)
		(fp_text user "${REFERENCE}"
			(at -0.95 -3.168 90)
			(layer "B.Fab")
			(effects
				(font
					(size 0.7 0.7)
					(thickness 0.15)
				)
				(justify left bottom mirror)
			)
		)
		(fp_text user "Author: Antmicro"
			(at -0.95 -4.169 90)
			(layer "B.Fab")
			(effects
				(font
					(size 0.7 0.7)
					(thickness 0.15)
				)
				(justify left bottom mirror)
			)
		)
		(fp_text user "License: Apache-2.0"
			(at -0.949999 -5.169 90)
			(layer "B.Fab")
			(effects
				(font
					(size 0.7 0.7)
					(thickness 0.15)
				)
				(justify left bottom mirror)
			)
		)
		(pad "1" smd roundrect
			(at -0.48 0 270)
			(size 0.59 0.64)
			(layers "B.Cu" "B.Mask" "B.Paste")
			(roundrect_rratio 0.25)
			(net 90 "/Peripherals/I2C_CONN_PEN")
			(pintype "passive")
		)
		(pad "2" smd roundrect
			(at 0.48 0 270)
			(size 0.59 0.64)
			(layers "B.Cu" "B.Mask" "B.Paste")
			(roundrect_rratio 0.25)
			(net 2 "+3V3")
			(pintype "passive")
		)
	)
)
